# SCM (Grand Teton) — schematic netlist excerpt (pin names and nets, part order shuffled) for the footprints in the layout excerpt that follows; sources: Cadence DE-HDL packaged netlist, KiCad conversion of 12092022_DA0F0TMDCD0_F0T_Management_Board_D_brd_V3_OCP.brd

PL32  Q_INDUCTOR  BLM18SN220TN1D/8000MA IND  pkg SMLF  page 56 : \1\ = P12V_AUX ; \2\ = SW_P1V0_AUX_FLT
H2  HOLE  EMPTY  pkg TH  page 57 : \1\ = NC

(kicad_pcb
	(version 20260206)
	(generator "pcbnew")
	(generator_version "10.0")
	(general
		(thickness 1.6)
		(legacy_teardrops no)
	)
	(paper "A4")
	(title_block
		(title "12092022_DA0F0TMDCD0_F0T_Management_Board_D_brd_V3_OCP.brd")
		(comment 1 "Grand Teton / footprints 45-46 of 1440")
	)
	(layers
		(0 "F.Cu" signal "TOP")
		(4 "In1.Cu" signal "GND")
		(6 "In2.Cu" signal "IN1")
		(8 "In3.Cu" signal "GND1")
		(10 "In4.Cu" signal "IN2")
		(12 "In5.Cu" signal "VCC")
		(14 "In6.Cu" signal "VCC1")
		(16 "In7.Cu" signal "IN3")
		(18 "In8.Cu" signal "GND2")
		(20 "In9.Cu" signal "IN4")
		(22 "In10.Cu" signal "GND3")
		(2 "B.Cu" signal "BOTTOM")
		(9 "F.Adhes" user "F.Adhesive")
		(11 "B.Adhes" user "B.Adhesive")
		(13 "F.Paste" user "Package Geometry/Pastemask Top")
		(15 "B.Paste" user "Package Geometry/Pastemask Bottom")
		(5 "F.SilkS" user "Ref Des/Silkscreen Top")
		(7 "B.SilkS" user "Ref Des/Silkscreen Bottom")
		(1 "F.Mask" user "Board Geometry/Soldermask Top")
		(3 "B.Mask" user "Board Geometry/Soldermask Bottom")
		(17 "Dwgs.User" user "User.Drawings")
		(19 "Cmts.User" user "User.Comments")
		(21 "Eco1.User" user "User.Eco1")
		(23 "Eco2.User" user "User.Eco2")
		(25 "Edge.Cuts" user "Board Geometry/Outline")
		(27 "Margin" user)
		(31 "F.CrtYd" user "Package Geometry/Place Bound Top")
		(29 "B.CrtYd" user "Package Geometry/Place Bound Bottom")
		(35 "F.Fab" user "Ref Des/Assembly Top")
		(33 "B.Fab" user "Ref Des/Assembly Bottom")
	)
	(footprint ""
		(layer "F.Cu")
		(at 20.447 -40.259 -90)
		(property "Reference" "PL32"
			(at 0 0 270)
			(layer "F.SilkS")
			(hide yes)
			(effects
				(font
					(size 1.27 1.27)
				)
			)
		)
		(property "Value" ""
			(at 0 0 270)
			(layer "F.Fab")
			(effects
				(font
					(size 1.27 1.27)
				)
			)
		)
		(duplicate_pad_numbers_are_jumpers no)
		(fp_line
			(start -1.27 0.5842)
			(end -1.27 -0.5842)
			(stroke
				(width 0.1524)
				(type default)
			)
			(layer "F.SilkS")
		)
		(fp_line
			(start -0.127 0.5842)
			(end -0.127 -0.5842)
			(stroke
				(width 0.1524)
				(type default)
			)
			(layer "F.SilkS")
		)
		(fp_line
			(start 0.127 0.5842)
			(end 0.127 -0.5842)
			(stroke
				(width 0.1524)
				(type default)
			)
			(layer "F.SilkS")
		)
		(fp_line
			(start 1.27 0.5842)
			(end -1.27 0.5842)
			(stroke
				(width 0.1524)
				(type default)
			)
			(layer "F.SilkS")
		)
		(fp_line
			(start 1.27 0.5842)
			(end 1.27 -0.5842)
			(stroke
				(width 0.1524)
				(type default)
			)
			(layer "F.SilkS")
		)
		(fp_line
			(start -1.27 -0.5588)
			(end -1.27 -0.5842)
			(stroke
				(width 0.1524)
				(type default)
			)
			(layer "F.SilkS")
		)
		(fp_line
			(start -1.27 -0.5842)
			(end 1.27 -0.5842)
			(stroke
				(width 0.1524)
				(type default)
			)
			(layer "F.SilkS")
		)
		(fp_line
			(start -0.9144 0.508)
			(end -0.9144 0.406654)
			(stroke
				(width 0.1)
				(type default)
			)
			(layer "F.Fab")
		)
		(fp_line
			(start 0.9144 0.508)
			(end -0.9144 0.508)
			(stroke
				(width 0.1)
				(type default)
			)
			(layer "F.Fab")
		)
		(fp_line
			(start -1.194308 0.406654)
			(end -1.194308 -0.406654)
			(stroke
				(width 0.1)
				(type default)
			)
			(layer "F.Fab")
		)
		(fp_line
			(start -0.9144 0.406654)
			(end -1.194308 0.406654)
			(stroke
				(width 0.1)
				(type default)
			)
			(layer "F.Fab")
		)
		(fp_line
			(start 0.9144 0.4064)
			(end 0.9144 0.508)
			(stroke
				(width 0.1)
				(type default)
			)
			(layer "F.Fab")
		)
		(fp_line
			(start 1.1938 0.4064)
			(end 0.9144 0.4064)
			(stroke
				(width 0.1)
				(type default)
			)
			(layer "F.Fab")
		)
		(fp_line
			(start -1.194308 -0.406654)
			(end -0.9144 -0.406654)
			(stroke
				(width 0.1)
				(type default)
			)
			(layer "F.Fab")
		)
		(fp_line
			(start -0.9144 -0.406654)
			(end -0.9144 -0.508)
			(stroke
				(width 0.1)
				(type default)
			)
			(layer "F.Fab")
		)
		(fp_line
			(start 0.9144 -0.406654)
			(end 1.1938 -0.406654)
			(stroke
				(width 0.1)
				(type default)
			)
			(layer "F.Fab")
		)
		(fp_line
			(start 1.1938 -0.406654)
			(end 1.1938 0.4064)
			(stroke
				(width 0.1)
				(type default)
			)
			(layer "F.Fab")
		)
		(fp_line
			(start -0.9144 -0.508)
			(end 0.9144 -0.508)
			(stroke
				(width 0.1)
				(type default)
			)
			(layer "F.Fab")
		)
		(fp_line
			(start 0.9144 -0.508)
			(end 0.9144 -0.406654)
			(stroke
				(width 0.1)
				(type default)
			)
			(layer "F.Fab")
		)
		(pad "1" smd rect
			(at -0.7366 0 180)
			(size 0.7112 0.8128)
			(layers "F.Cu" "F.Mask" "F.Paste")
			(net "P12V_AUX")
		)
		(pad "2" smd rect
			(at 0.7366 0 180)
			(size 0.7112 0.8128)
			(layers "F.Cu" "F.Mask" "F.Paste")
			(net "SW_P1V0_AUX_FLT")
		)
	)
	(footprint ""
		(layer "F.Cu")
		(at 26.75001 -47.389034)
		(property "Reference" "H2"
			(at -2.4892 -4.562348 0)
			(unlocked yes)
			(layer "F.SilkS")
			(effects
				(font
					(size 0.7874 0.5842)
					(thickness 0.1524)
				)
			)
		)
		(property "Value" ""
			(at 0 0 0)
			(layer "F.Fab")
			(effects
				(font
					(size 1.27 1.27)
				)
			)
		)
		(duplicate_pad_numbers_are_jumpers no)
		(pad "" np_thru_hole circle
			(at 0 0)
			(size 0 0)
			(drill oval 3.2004 4.8006)
			(layers "*.Cu" "*.Mask")
			(clearance -1.2192)
			(thermal_gap 0.381)
			(padstack
				(mode front_inner_back)
				(layer "Inner"
					(shape oval)
					(size 3.2004 4.8006)
					(clearance 0.381)
				)
				(layer "B.Cu"
					(shape circle)
					(size 0 0)
					(clearance -1.2192)
				)
			)
		)
		(zone
			(layers "F.Cu" "B.Cu" "In1.Cu" "In2.Cu" "In3.Cu" "In4.Cu" "In5.Cu" "In6.Cu"
				"In7.Cu" "In8.Cu" "In9.Cu" "In10.Cu"
			)
			(hatch none 0.5)
			(connect_pads
				(clearance 0)
			)
			(min_thickness 0.25)
			(keepout
				(tracks not_allowed)
				(vias allowed)
				(pads allowed)
				(copperpour not_allowed)
				(footprints allowed)
			)
			(placement
				(enabled no)
				(sheetname "")
			)
			(fill
				(thermal_gap 0.5)
				(thermal_bridge_width 0.5)
				(island_removal_mode 0)
			)
			(polygon
				(pts
					(arc
						(start 28.85821 -46.588934)
						(mid 26.75001 -44.480734)
						(end 24.64181 -46.588934)
					)
					(arc
						(start 24.64181 -48.189134)
						(mid 26.75001 -50.297334)
						(end 28.85821 -48.189134)
					)
				)
			)
		)
		(zone
			(layers "F.Cu" "B.Cu" "In1.Cu" "In2.Cu" "In3.Cu" "In4.Cu" "In5.Cu" "In6.Cu"
				"In7.Cu" "In8.Cu" "In9.Cu" "In10.Cu"
			)
			(hatch none 0.5)
			(connect_pads
				(clearance 0)
			)
			(min_thickness 0.25)
			(keepout
				(tracks not_allowed)
				(vias allowed)
				(pads allowed)
				(copperpour not_allowed)
				(footprints allowed)
			)
			(placement
				(enabled no)
				(sheetname "")
			)
			(fill
				(thermal_gap 0.5)
				(thermal_bridge_width 0.5)
				(island_removal_mode 0)
			)
			(polygon
				(pts
					(arc
						(start 29.750258 -46.588934)
						(mid 26.75001 -43.588686)
						(end 23.749762 -46.588934)
					)
					(arc
						(start 23.749762 -48.189134)
						(mid 26.75001 -51.189382)
						(end 29.750258 -48.189134)
					)
				)
			)
		)
	)
)
